(kicad_pcb
	(version 20260206)
	(generator "pcbnew")
	(generator_version "10.0")
	(general
		(thickness 1.6)
		(legacy_teardrops no)
	)
	(paper "A4")
	(title_block
		(title "12092022_DA0F0TFB6D0_F0T_FAN_BOARD_MP5048_D_brd_v02_OCP.brd")
		(comment 1 "Grand Teton / footprints 74-76 of 924")
	)
	(layers
		(0 "F.Cu" signal "TOP")
		(4 "In1.Cu" signal "GND")
		(6 "In2.Cu" signal "IN1")
		(8 "In3.Cu" signal "IN2")
		(10 "In4.Cu" signal "GND1")
		(2 "B.Cu" signal "BOTTOM")
		(9 "F.Adhes" user "F.Adhesive")
		(11 "B.Adhes" user "B.Adhesive")
		(13 "F.Paste" user "Package Geometry/Pastemask Top")
		(15 "B.Paste" user "Package Geometry/Pastemask Bottom")
		(5 "F.SilkS" user "Ref Des/Silkscreen Top")
		(7 "B.SilkS" user "Ref Des/Silkscreen Bottom")
		(1 "F.Mask" user "Board Geometry/Soldermask Top")
		(3 "B.Mask" user "Board Geometry/Soldermask Bottom")
		(17 "Dwgs.User" user "User.Drawings")
		(19 "Cmts.User" user "User.Comments")
		(21 "Eco1.User" user "User.Eco1")
		(23 "Eco2.User" user "User.Eco2")
		(25 "Edge.Cuts" user "Board Geometry/Outline")
		(27 "Margin" user)
		(31 "F.CrtYd" user "Package Geometry/Place Bound Top")
		(29 "B.CrtYd" user "Package Geometry/Place Bound Bottom")
		(35 "F.Fab" user "Ref Des/Assembly Top")
		(33 "B.Fab" user "Ref Des/Assembly Bottom")
	)
	(footprint ""
		(layer "F.Cu")
		(at 9.906 -164.084 180)
		(property "Reference" "U23"
			(at 2.00533 -1.016 90)
			(unlocked yes)
			(layer "F.SilkS")
			(effects
				(font
					(size 0.7874 0.5842)
					(thickness 0.1524)
				)
				(justify left)
			)
		)
		(property "Value" ""
			(at 0 0 180)
			(layer "F.Fab")
			(effects
				(font
					(size 1.27 1.27)
				)
			)
		)
		(duplicate_pad_numbers_are_jumpers no)
		(fp_line
			(start 1.3462 1.100074)
			(end -1.3462 1.100074)
			(stroke
				(width 0.1524)
				(type default)
			)
			(layer "F.SilkS")
		)
		(fp_line
			(start 1.3462 -1.100074)
			(end 1.3462 1.100074)
			(stroke
				(width 0.1524)
				(type default)
			)
			(layer "F.SilkS")
		)
		(fp_line
			(start 0.670052 -1.100074)
			(end 1.3462 -1.100074)
			(stroke
				(width 0.1524)
				(type default)
			)
			(layer "F.SilkS")
		)
		(fp_line
			(start 0 -0.381)
			(end 0.670052 -1.100074)
			(stroke
				(width 0.1524)
				(type default)
			)
			(layer "F.SilkS")
		)
		(fp_line
			(start -0.670052 -1.100074)
			(end 0 -0.381)
			(stroke
				(width 0.1524)
				(type default)
			)
			(layer "F.SilkS")
		)
		(fp_line
			(start -1.3462 1.100074)
			(end -1.3462 -1.100074)
			(stroke
				(width 0.1524)
				(type default)
			)
			(layer "F.SilkS")
		)
		(fp_line
			(start -1.3462 -1.100074)
			(end -0.670052 -1.100074)
			(stroke
				(width 0.1524)
				(type default)
			)
			(layer "F.SilkS")
		)
		(fp_poly
			(pts
				(xy -1.524 -0.649986) (xy -2.286 -1.030986) (xy -2.286 -0.268986)
			)
			(stroke
				(width 0)
				(type default)
			)
			(fill yes)
			(layer "F.SilkS")
		)
		(fp_line
			(start 1.100074 0.8001)
			(end 0.670052 0.8001)
			(stroke
				(width 0.1)
				(type default)
			)
			(layer "F.Fab")
		)
		(fp_line
			(start 1.100074 -0.8001)
			(end 1.100074 0.8001)
			(stroke
				(width 0.1)
				(type default)
			)
			(layer "F.Fab")
		)
		(fp_line
			(start 0.670052 1.100074)
			(end -0.670052 1.100074)
			(stroke
				(width 0.1)
				(type default)
			)
			(layer "F.Fab")
		)
		(fp_line
			(start 0.670052 0.8001)
			(end 0.670052 1.100074)
			(stroke
				(width 0.1)
				(type default)
			)
			(layer "F.Fab")
		)
		(fp_line
			(start 0.670052 -0.8001)
			(end 1.100074 -0.8001)
			(stroke
				(width 0.1)
				(type default)
			)
			(layer "F.Fab")
		)
		(fp_line
			(start 0.670052 -0.8001)
			(end 0.670052 0.8001)
			(stroke
				(width 0.1)
				(type default)
			)
			(layer "F.Fab")
		)
		(fp_line
			(start 0.670052 -1.100074)
			(end 0.670052 -0.8001)
			(stroke
				(width 0.1)
				(type default)
			)
			(layer "F.Fab")
		)
		(fp_line
			(start -0.670052 1.100074)
			(end -0.670052 0.8001)
			(stroke
				(width 0.1)
				(type default)
			)
			(layer "F.Fab")
		)
		(fp_line
			(start -0.670052 0.8001)
			(end -0.670052 -0.8001)
			(stroke
				(width 0.1)
				(type default)
			)
			(layer "F.Fab")
		)
		(fp_line
			(start -0.670052 0.8001)
			(end -1.100074 0.8001)
			(stroke
				(width 0.1)
				(type default)
			)
			(layer "F.Fab")
		)
		(fp_line
			(start -0.670052 -0.8001)
			(end -0.670052 -1.100074)
			(stroke
				(width 0.1)
				(type default)
			)
			(layer "F.Fab")
		)
		(fp_line
			(start -0.670052 -1.100074)
			(end 0.670052 -1.100074)
			(stroke
				(width 0.1)
				(type default)
			)
			(layer "F.Fab")
		)
		(fp_line
			(start -1.100074 0.8001)
			(end -1.100074 -0.8001)
			(stroke
				(width 0.1)
				(type default)
			)
			(layer "F.Fab")
		)
		(fp_line
			(start -1.100074 -0.8001)
			(end -0.670052 -0.8001)
			(stroke
				(width 0.1)
				(type default)
			)
			(layer "F.Fab")
		)
		(fp_poly
			(pts
				(xy -1.524 -0.649986) (xy -2.286 -1.030986) (xy -2.286 -0.268986)
			)
			(stroke
				(width 0)
				(type default)
			)
			(fill yes)
			(layer "F.Fab")
		)
		(pad "1" smd rect
			(at -0.94996 -0.649986 90)
			(size 0.4064 0.508)
			(layers "F.Cu" "F.Mask" "F.Paste")
			(net "FAN_0_PRESENT_N")
		)
		(pad "2" smd rect
			(at -0.94996 0 90)
			(size 0.4064 0.508)
			(layers "F.Cu" "F.Mask" "F.Paste")
			(net "GND")
		)
		(pad "3" smd rect
			(at -0.94996 0.649986 90)
			(size 0.4064 0.508)
			(layers "F.Cu" "F.Mask" "F.Paste")
			(net "FAN_1_PRESENT_N")
		)
		(pad "4" smd rect
			(at 0.94996 0.649986 90)
			(size 0.4064 0.508)
			(layers "F.Cu" "F.Mask" "F.Paste")
			(net "FAN_1_PRSNT_BUF_R_N")
		)
		(pad "5" smd rect
			(at 0.94996 0 90)
			(size 0.4064 0.508)
			(layers "F.Cu" "F.Mask" "F.Paste")
			(net "P3V3_AUX")
		)
		(pad "6" smd rect
			(at 0.94996 -0.649986 90)
			(size 0.4064 0.508)
			(layers "F.Cu" "F.Mask" "F.Paste")
			(net "FAN_0_PRSNT_BUF_R_N")
		)
	)
	(footprint ""
		(layer "F.Cu")
		(at 42.291 -135.509 -90)
		(property "Reference" "R5562"
			(at 0 0 270)
			(layer "F.SilkS")
			(hide yes)
			(effects
				(font
					(size 1.27 1.27)
				)
			)
		)
		(property "Value" ""
			(at 0 0 270)
			(layer "F.Fab")
			(effects
				(font
					(size 1.27 1.27)
				)
			)
		)
		(duplicate_pad_numbers_are_jumpers no)
		(fp_line
			(start -0.7874 0.4064)
			(end -0.7874 -0.4064)
			(stroke
				(width 0.1524)
				(type default)
			)
			(layer "F.SilkS")
		)
		(fp_line
			(start 0.7874 0.4064)
			(end -0.7874 0.4064)
			(stroke
				(width 0.1524)
				(type default)
			)
			(layer "F.SilkS")
		)
		(fp_line
			(start -0.7874 -0.4064)
			(end 0.7874 -0.4064)
			(stroke
				(width 0.1524)
				(type default)
			)
			(layer "F.SilkS")
		)
		(fp_line
			(start 0.7874 -0.4064)
			(end 0.7874 0.4064)
			(stroke
				(width 0.1524)
				(type default)
			)
			(layer "F.SilkS")
		)
		(fp_line
			(start -0.67945 0.3048)
			(end -0.67945 -0.305054)
			(stroke
				(width 0.1)
				(type default)
			)
			(layer "F.Fab")
		)
		(fp_line
			(start -0.12065 0.3048)
			(end -0.67945 0.3048)
			(stroke
				(width 0.1)
				(type default)
			)
			(layer "F.Fab")
		)
		(fp_line
			(start 0.120396 0.3048)
			(end 0.120396 0.2794)
			(stroke
				(width 0.1)
				(type default)
			)
			(layer "F.Fab")
		)
		(fp_line
			(start 0.67945 0.3048)
			(end 0.120396 0.3048)
			(stroke
				(width 0.1)
				(type default)
			)
			(layer "F.Fab")
		)
		(fp_line
			(start -0.12065 0.2794)
			(end -0.12065 0.3048)
			(stroke
				(width 0.1)
				(type default)
			)
			(layer "F.Fab")
		)
		(fp_line
			(start 0.120396 0.2794)
			(end -0.12065 0.2794)
			(stroke
				(width 0.1)
				(type default)
			)
			(layer "F.Fab")
		)
		(fp_line
			(start -0.12065 -0.2794)
			(end 0.12065 -0.2794)
			(stroke
				(width 0.1)
				(type default)
			)
			(layer "F.Fab")
		)
		(fp_line
			(start 0.12065 -0.2794)
			(end 0.12065 -0.3048)
			(stroke
				(width 0.1)
				(type default)
			)
			(layer "F.Fab")
		)
		(fp_line
			(start 0.12065 -0.3048)
			(end 0.67945 -0.3048)
			(stroke
				(width 0.1)
				(type default)
			)
			(layer "F.Fab")
		)
		(fp_line
			(start 0.67945 -0.3048)
			(end 0.67945 0.3048)
			(stroke
				(width 0.1)
				(type default)
			)
			(layer "F.Fab")
		)
		(fp_line
			(start -0.67945 -0.305054)
			(end -0.12065 -0.305054)
			(stroke
				(width 0.1)
				(type default)
			)
			(layer "F.Fab")
		)
		(fp_line
			(start -0.12065 -0.305054)
			(end -0.12065 -0.2794)
			(stroke
				(width 0.1)
				(type default)
			)
			(layer "F.Fab")
		)
		(pad "1" smd circle
			(at -0.40005 0 270)
			(size 0 0)
			(layers "F.Cu" "F.Mask" "F.Paste")
			(net "P3V3_AUX")
		)
		(pad "2" smd circle
			(at 0.40005 0 270)
			(size 0 0)
			(layers "F.Cu" "F.Mask" "F.Paste")
			(net "U403_ADD2")
		)
	)
	(footprint ""
		(layer "F.Cu")
		(at 35.179 -27.391868 180)
		(property "Reference" "C2053"
			(at 0 0 180)
			(layer "F.SilkS")
			(hide yes)
			(effects
				(font
					(size 1.27 1.27)
				)
			)
		)
		(property "Value" ""
			(at 0 0 180)
			(layer "F.Fab")
			(effects
				(font
					(size 1.27 1.27)
				)
			)
		)
		(duplicate_pad_numbers_are_jumpers no)
		(fp_line
			(start 0.7874 0.4064)
			(end -0.7874 0.4064)
			(stroke
				(width 0.1524)
				(type default)
			)
			(layer "F.SilkS")
		)
		(fp_line
			(start 0.7874 -0.4064)
			(end 0.7874 0.4064)
			(stroke
				(width 0.1524)
				(type default)
			)
			(layer "F.SilkS")
		)
		(fp_line
			(start -0.7874 0.4064)
			(end -0.7874 -0.4064)
			(stroke
				(width 0.1524)
				(type default)
			)
			(layer "F.SilkS")
		)
		(fp_line
			(start -0.7874 -0.4064)
			(end 0.7874 -0.4064)
			(stroke
				(width 0.1524)
				(type default)
			)
			(layer "F.SilkS")
		)
		(fp_line
			(start 0.67945 0.3048)
			(end 0.120396 0.3048)
			(stroke
				(width 0.1)
				(type default)
			)
			(layer "F.Fab")
		)
		(fp_line
			(start 0.67945 -0.3048)
			(end 0.67945 0.3048)
			(stroke
				(width 0.1)
				(type default)
			)
			(layer "F.Fab")
		)
		(fp_line
			(start 0.12065 -0.2794)
			(end 0.12065 -0.3048)
			(stroke
				(width 0.1)
				(type default)
			)
			(layer "F.Fab")
		)
		(fp_line
			(start 0.12065 -0.3048)
			(end 0.67945 -0.3048)
			(stroke
				(width 0.1)
				(type default)
			)
			(layer "F.Fab")
		)
		(fp_line
			(start 0.120396 0.3048)
			(end 0.120396 0.2794)
			(stroke
				(width 0.1)
				(type default)
			)
			(layer "F.Fab")
		)
		(fp_line
			(start 0.120396 0.2794)
			(end -0.12065 0.2794)
			(stroke
				(width 0.1)
				(type default)
			)
			(layer "F.Fab")
		)
		(fp_line
			(start -0.12065 0.3048)
			(end -0.67945 0.3048)
			(stroke
				(width 0.1)
				(type default)
			)
			(layer "F.Fab")
		)
		(fp_line
			(start -0.12065 0.2794)
			(end -0.12065 0.3048)
			(stroke
				(width 0.1)
				(type default)
			)
			(layer "F.Fab")
		)
		(fp_line
			(start -0.12065 -0.2794)
			(end 0.12065 -0.2794)
			(stroke
				(width 0.1)
				(type default)
			)
			(layer "F.Fab")
		)
		(fp_line
			(start -0.12065 -0.305054)
			(end -0.12065 -0.2794)
			(stroke
				(width 0.1)
				(type default)
			)
			(layer "F.Fab")
		)
		(fp_line
			(start -0.67945 0.3048)
			(end -0.67945 -0.305054)
			(stroke
				(width 0.1)
				(type default)
			)
			(layer "F.Fab")
		)
		(fp_line
			(start -0.67945 -0.305054)
			(end -0.12065 -0.305054)
			(stroke
				(width 0.1)
				(type default)
			)
			(layer "F.Fab")
		)
		(pad "1" smd circle
			(at -0.40005 0 180)
			(size 0 0)
			(layers "F.Cu" "F.Mask" "F.Paste")
			(net "FAN_3_PWM_IL_R")
		)
		(pad "2" smd circle
			(at 0.40005 0 180)
			(size 0 0)
			(layers "F.Cu" "F.Mask" "F.Paste")
			(net "GND")
		)
	)
)
